(kicad_pcb
	(version 20260206)
	(generator "pcbnew")
	(generator_version "10.0")
	(general
		(thickness 1.6)
		(legacy_teardrops no)
	)
	(paper "A4")
	(title_block
		(title "03242023_DA0F0TMBIJ0_F0T_Motherboard_J_brd_V01_OCP.brd")
		(comment 1 "Grand Teton / footprints 1912-1916 of 6105")
	)
	(layers
		(0 "F.Cu" signal "TOP")
		(4 "In1.Cu" signal "GND")
		(6 "In2.Cu" signal "IN1")
		(8 "In3.Cu" signal "GND1")
		(10 "In4.Cu" signal "IN2")
		(12 "In5.Cu" signal "GND2")
		(14 "In6.Cu" signal "IN3")
		(16 "In7.Cu" signal "GND3")
		(18 "In8.Cu" signal "VCC")
		(20 "In9.Cu" signal "VCC1")
		(22 "In10.Cu" signal "GND4")
		(24 "In11.Cu" signal "IN4")
		(26 "In12.Cu" signal "GND5")
		(28 "In13.Cu" signal "IN5")
		(30 "In14.Cu" signal "GND6")
		(32 "In15.Cu" signal "IN6")
		(34 "In16.Cu" signal "GND7")
		(2 "B.Cu" signal "BOTTOM")
		(9 "F.Adhes" user "F.Adhesive")
		(11 "B.Adhes" user "B.Adhesive")
		(13 "F.Paste" user "Package Geometry/Pastemask Top")
		(15 "B.Paste" user "Package Geometry/Pastemask Bottom")
		(5 "F.SilkS" user "Ref Des/Silkscreen Top")
		(7 "B.SilkS" user "Ref Des/Silkscreen Bottom")
		(1 "F.Mask" user "Board Geometry/Soldermask Top")
		(3 "B.Mask" user "Board Geometry/Soldermask Bottom")
		(17 "Dwgs.User" user "User.Drawings")
		(19 "Cmts.User" user "User.Comments")
		(21 "Eco1.User" user "User.Eco1")
		(23 "Eco2.User" user "User.Eco2")
		(25 "Edge.Cuts" user "Board Geometry/Outline")
		(27 "Margin" user)
		(31 "F.CrtYd" user "Package Geometry/Place Bound Top")
		(29 "B.CrtYd" user "Package Geometry/Place Bound Bottom")
		(35 "F.Fab" user "Ref Des/Assembly Top")
		(33 "B.Fab" user "Ref Des/Assembly Bottom")
	)
	(footprint ""
		(layer "F.Cu")
		(at 73.28408 -143.769588 180)
		(property "Reference" "PR568"
			(at 0 0 180)
			(layer "F.SilkS")
			(hide yes)
			(effects
				(font
					(size 1.27 1.27)
				)
			)
		)
		(property "Value" ""
			(at 0 0 180)
			(layer "F.Fab")
			(effects
				(font
					(size 1.27 1.27)
				)
			)
		)
		(duplicate_pad_numbers_are_jumpers no)
		(fp_line
			(start 0.7874 0.4064)
			(end -0.7874 0.4064)
			(stroke
				(width 0.1524)
				(type default)
			)
			(layer "F.SilkS")
		)
		(fp_line
			(start 0.7874 -0.4064)
			(end 0.7874 0.4064)
			(stroke
				(width 0.1524)
				(type default)
			)
			(layer "F.SilkS")
		)
		(fp_line
			(start -0.7874 0.4064)
			(end -0.7874 -0.4064)
			(stroke
				(width 0.1524)
				(type default)
			)
			(layer "F.SilkS")
		)
		(fp_line
			(start -0.7874 -0.4064)
			(end 0.7874 -0.4064)
			(stroke
				(width 0.1524)
				(type default)
			)
			(layer "F.SilkS")
		)
		(fp_line
			(start 0.67945 0.3048)
			(end 0.120396 0.3048)
			(stroke
				(width 0.1)
				(type default)
			)
			(layer "F.Fab")
		)
		(fp_line
			(start 0.67945 -0.3048)
			(end 0.67945 0.3048)
			(stroke
				(width 0.1)
				(type default)
			)
			(layer "F.Fab")
		)
		(fp_line
			(start 0.12065 -0.2794)
			(end 0.12065 -0.3048)
			(stroke
				(width 0.1)
				(type default)
			)
			(layer "F.Fab")
		)
		(fp_line
			(start 0.12065 -0.3048)
			(end 0.67945 -0.3048)
			(stroke
				(width 0.1)
				(type default)
			)
			(layer "F.Fab")
		)
		(fp_line
			(start 0.120396 0.3048)
			(end 0.120396 0.2794)
			(stroke
				(width 0.1)
				(type default)
			)
			(layer "F.Fab")
		)
		(fp_line
			(start 0.120396 0.2794)
			(end -0.12065 0.2794)
			(stroke
				(width 0.1)
				(type default)
			)
			(layer "F.Fab")
		)
		(fp_line
			(start -0.12065 0.3048)
			(end -0.67945 0.3048)
			(stroke
				(width 0.1)
				(type default)
			)
			(layer "F.Fab")
		)
		(fp_line
			(start -0.12065 0.2794)
			(end -0.12065 0.3048)
			(stroke
				(width 0.1)
				(type default)
			)
			(layer "F.Fab")
		)
		(fp_line
			(start -0.12065 -0.2794)
			(end 0.12065 -0.2794)
			(stroke
				(width 0.1)
				(type default)
			)
			(layer "F.Fab")
		)
		(fp_line
			(start -0.12065 -0.305054)
			(end -0.12065 -0.2794)
			(stroke
				(width 0.1)
				(type default)
			)
			(layer "F.Fab")
		)
		(fp_line
			(start -0.67945 0.3048)
			(end -0.67945 -0.305054)
			(stroke
				(width 0.1)
				(type default)
			)
			(layer "F.Fab")
		)
		(fp_line
			(start -0.67945 -0.305054)
			(end -0.12065 -0.305054)
			(stroke
				(width 0.1)
				(type default)
			)
			(layer "F.Fab")
		)
		(pad "1" smd circle
			(at -0.40005 0 180)
			(size 0 0)
			(layers "F.Cu" "F.Mask" "F.Paste")
			(net "VSENSE_PVCCINFAON_CPU1_DP")
		)
		(pad "2" smd circle
			(at 0.40005 0 180)
			(size 0 0)
			(layers "F.Cu" "F.Mask" "F.Paste")
			(net "PVCCINFAON_CPU1")
		)
	)
	(footprint ""
		(layer "F.Cu")
		(at 299.02023 -55.416196)
		(property "Reference" "R2979"
			(at 0 0 0)
			(layer "F.SilkS")
			(hide yes)
			(effects
				(font
					(size 1.27 1.27)
				)
			)
		)
		(property "Value" ""
			(at 0 0 0)
			(layer "F.Fab")
			(effects
				(font
					(size 1.27 1.27)
				)
			)
		)
		(duplicate_pad_numbers_are_jumpers no)
		(fp_line
			(start -0.7874 -0.4064)
			(end 0.7874 -0.4064)
			(stroke
				(width 0.1524)
				(type default)
			)
			(layer "F.SilkS")
		)
		(fp_line
			(start -0.7874 0.4064)
			(end -0.7874 -0.4064)
			(stroke
				(width 0.1524)
				(type default)
			)
			(layer "F.SilkS")
		)
		(fp_line
			(start 0.7874 -0.4064)
			(end 0.7874 0.4064)
			(stroke
				(width 0.1524)
				(type default)
			)
			(layer "F.SilkS")
		)
		(fp_line
			(start 0.7874 0.4064)
			(end -0.7874 0.4064)
			(stroke
				(width 0.1524)
				(type default)
			)
			(layer "F.SilkS")
		)
		(fp_line
			(start -0.67945 -0.305054)
			(end -0.12065 -0.305054)
			(stroke
				(width 0.1)
				(type default)
			)
			(layer "F.Fab")
		)
		(fp_line
			(start -0.67945 0.3048)
			(end -0.67945 -0.305054)
			(stroke
				(width 0.1)
				(type default)
			)
			(layer "F.Fab")
		)
		(fp_line
			(start -0.12065 -0.305054)
			(end -0.12065 -0.2794)
			(stroke
				(width 0.1)
				(type default)
			)
			(layer "F.Fab")
		)
		(fp_line
			(start -0.12065 -0.2794)
			(end 0.12065 -0.2794)
			(stroke
				(width 0.1)
				(type default)
			)
			(layer "F.Fab")
		)
		(fp_line
			(start -0.12065 0.2794)
			(end -0.12065 0.3048)
			(stroke
				(width 0.1)
				(type default)
			)
			(layer "F.Fab")
		)
		(fp_line
			(start -0.12065 0.3048)
			(end -0.67945 0.3048)
			(stroke
				(width 0.1)
				(type default)
			)
			(layer "F.Fab")
		)
		(fp_line
			(start 0.120396 0.2794)
			(end -0.12065 0.2794)
			(stroke
				(width 0.1)
				(type default)
			)
			(layer "F.Fab")
		)
		(fp_line
			(start 0.120396 0.3048)
			(end 0.120396 0.2794)
			(stroke
				(width 0.1)
				(type default)
			)
			(layer "F.Fab")
		)
		(fp_line
			(start 0.12065 -0.3048)
			(end 0.67945 -0.3048)
			(stroke
				(width 0.1)
				(type default)
			)
			(layer "F.Fab")
		)
		(fp_line
			(start 0.12065 -0.2794)
			(end 0.12065 -0.3048)
			(stroke
				(width 0.1)
				(type default)
			)
			(layer "F.Fab")
		)
		(fp_line
			(start 0.67945 -0.3048)
			(end 0.67945 0.3048)
			(stroke
				(width 0.1)
				(type default)
			)
			(layer "F.Fab")
		)
		(fp_line
			(start 0.67945 0.3048)
			(end 0.120396 0.3048)
			(stroke
				(width 0.1)
				(type default)
			)
			(layer "F.Fab")
		)
		(pad "1" smd circle
			(at -0.40005 0)
			(size 0 0)
			(layers "F.Cu" "F.Mask" "F.Paste")
			(net "P1V05_PCH_AUX")
		)
		(pad "2" smd circle
			(at 0.40005 0)
			(size 0 0)
			(layers "F.Cu" "F.Mask" "F.Paste")
			(net "FM_BOARD_SKU_ID2")
		)
	)
	(footprint ""
		(layer "F.Cu")
		(at 140.73378 -121.211848)
		(property "Reference" "U51"
			(at -2.2606 -4.663948 0)
			(unlocked yes)
			(layer "F.SilkS")
			(effects
				(font
					(size 0.7874 0.5842)
					(thickness 0.1524)
				)
				(justify left)
			)
		)
		(property "Value" ""
			(at 0 0 0)
			(layer "F.Fab")
			(effects
				(font
					(size 1.27 1.27)
				)
			)
		)
		(duplicate_pad_numbers_are_jumpers no)
		(fp_line
			(start -2.097532 -3.949954)
			(end -2.097532 3.949954)
			(stroke
				(width 0.1524)
				(type default)
			)
			(layer "F.SilkS")
		)
		(fp_line
			(start -2.097532 3.949954)
			(end 2.097532 3.949954)
			(stroke
				(width 0.1524)
				(type default)
			)
			(layer "F.SilkS")
		)
		(fp_line
			(start -1.409954 -3.949954)
			(end -2.097532 -3.949954)
			(stroke
				(width 0.1524)
				(type default)
			)
			(layer "F.SilkS")
		)
		(fp_line
			(start 0 -2.54)
			(end -1.409954 -3.949954)
			(stroke
				(width 0.1524)
				(type default)
			)
			(layer "F.SilkS")
		)
		(fp_line
			(start 1.409954 -3.949954)
			(end 0 -2.54)
			(stroke
				(width 0.1524)
				(type default)
			)
			(layer "F.SilkS")
		)
		(fp_line
			(start 2.097532 -3.949954)
			(end 1.409954 -3.949954)
			(stroke
				(width 0.1524)
				(type default)
			)
			(layer "F.SilkS")
		)
		(fp_line
			(start 2.097532 3.949954)
			(end 2.097532 -3.949954)
			(stroke
				(width 0.1524)
				(type default)
			)
			(layer "F.SilkS")
		)
		(fp_poly
			(pts
				(xy -4.7498 -4.182872) (xy -4.7498 -3.166872) (xy -3.7338 -3.674872)
			)
			(stroke
				(width 0)
				(type default)
			)
			(fill yes)
			(layer "F.SilkS")
		)
		(fp_line
			(start -2.249932 -3.949954)
			(end -2.249932 3.949954)
			(stroke
				(width 0.1)
				(type default)
			)
			(layer "F.Fab")
		)
		(fp_line
			(start -2.249932 3.949954)
			(end 2.249932 3.949954)
			(stroke
				(width 0.1)
				(type default)
			)
			(layer "F.Fab")
		)
		(fp_line
			(start 2.249932 -3.949954)
			(end -2.249932 -3.949954)
			(stroke
				(width 0.1)
				(type default)
			)
			(layer "F.Fab")
		)
		(fp_line
			(start 2.249932 3.949954)
			(end 2.249932 -3.949954)
			(stroke
				(width 0.1)
				(type default)
			)
			(layer "F.Fab")
		)
		(fp_poly
			(pts
				(xy -4.7498 -4.182872) (xy -4.7498 -3.166872) (xy -3.7338 -3.674872)
			)
			(stroke
				(width 0)
				(type default)
			)
			(fill yes)
			(layer "F.Fab")
		)
		(pad "1" smd rect
			(at -2.925064 -3.674872 270)
			(size 0.6096 1.3716)
			(layers "F.Cu" "F.Mask" "F.Paste")
			(net "FM_SMB_CPU1_ALERT")
		)
		(pad "2" smd rect
			(at -2.925064 -2.925064 270)
			(size 0.4064 1.3716)
			(layers "F.Cu" "F.Mask" "F.Paste")
			(net "PD_SMB_OCP2_HP_ADD1")
		)
		(pad "3" smd rect
			(at -2.925064 -2.275078 270)
			(size 0.4064 1.3716)
			(layers "F.Cu" "F.Mask" "F.Paste")
			(net "PD_SMB_OCP2_HP_ADD2")
		)
		(pad "4" smd rect
			(at -2.925064 -1.625092 270)
			(size 0.4064 1.3716)
			(layers "F.Cu" "F.Mask" "F.Paste")
			(net "TP_PCA9555_U51_P00")
		)
		(pad "5" smd rect
			(at -2.925064 -0.975106 270)
			(size 0.4064 1.3716)
			(layers "F.Cu" "F.Mask" "F.Paste")
			(net "TP_PCA9555_U51_P01")
		)
		(pad "6" smd rect
			(at -2.925064 -0.32512 270)
			(size 0.4064 1.3716)
			(layers "F.Cu" "F.Mask" "F.Paste")
			(net "HP_OCP_V3_2_EN")
		)
		(pad "7" smd rect
			(at -2.925064 0.32512 270)
			(size 0.4064 1.3716)
			(layers "F.Cu" "F.Mask" "F.Paste")
			(net "HP_LVC3_OCP_V3_2_ATTN_OUT_SW_N")
		)
		(pad "8" smd rect
			(at -2.925064 0.975106 270)
			(size 0.4064 1.3716)
			(layers "F.Cu" "F.Mask" "F.Paste")
			(net "HP_LVC3_OCP_V3_2_PRSNT2_N")
		)
		(pad "9" smd rect
			(at -2.925064 1.625092 270)
			(size 0.4064 1.3716)
			(layers "F.Cu" "F.Mask" "F.Paste")
			(net "TP_PCA9555_U51_P05")
		)
		(pad "10" smd rect
			(at -2.925064 2.275078 270)
			(size 0.4064 1.3716)
			(layers "F.Cu" "F.Mask" "F.Paste")
			(net "TP_PCA9555_U51_P06")
		)
		(pad "11" smd rect
			(at -2.925064 2.925064 270)
			(size 0.4064 1.3716)
			(layers "F.Cu" "F.Mask" "F.Paste")
			(net "TP_PCA9555_U51_P07")
		)
		(pad "12" smd rect
			(at -2.925064 3.674872 270)
			(size 0.6096 1.3716)
			(layers "F.Cu" "F.Mask" "F.Paste")
			(net "GND")
		)
		(pad "13" smd rect
			(at 2.925064 3.674872 270)
			(size 0.6096 1.3716)
			(layers "F.Cu" "F.Mask" "F.Paste")
			(net "TP_PCA9555_U51_P10")
		)
		(pad "14" smd rect
			(at 2.925064 2.925064 270)
			(size 0.4064 1.3716)
			(layers "F.Cu" "F.Mask" "F.Paste")
			(net "TP_PCA9555_U51_P11")
		)
		(pad "15" smd rect
			(at 2.925064 2.275078 270)
			(size 0.4064 1.3716)
			(layers "F.Cu" "F.Mask" "F.Paste")
			(net "TP_PCA9555_U51_P12")
		)
		(pad "16" smd rect
			(at 2.925064 1.625092 270)
			(size 0.4064 1.3716)
			(layers "F.Cu" "F.Mask" "F.Paste")
			(net "TP_PCA9555_U51_P13")
		)
		(pad "17" smd rect
			(at 2.925064 0.975106 270)
			(size 0.4064 1.3716)
			(layers "F.Cu" "F.Mask" "F.Paste")
			(net "TP_PCA9555_U51_P14")
		)
		(pad "18" smd rect
			(at 2.925064 0.32512 270)
			(size 0.4064 1.3716)
			(layers "F.Cu" "F.Mask" "F.Paste")
			(net "TP_PCA9555_U51_P15")
		)
		(pad "19" smd rect
			(at 2.925064 -0.32512 270)
			(size 0.4064 1.3716)
			(layers "F.Cu" "F.Mask" "F.Paste")
			(net "TP_PCA9555_U51_P16")
		)
		(pad "20" smd rect
			(at 2.925064 -0.975106 270)
			(size 0.4064 1.3716)
			(layers "F.Cu" "F.Mask" "F.Paste")
			(net "TP_PCA9555_U51_P17")
		)
		(pad "21" smd rect
			(at 2.925064 -1.625092 270)
			(size 0.4064 1.3716)
			(layers "F.Cu" "F.Mask" "F.Paste")
			(net "PD_SMB_OCP2_HP_ADD0")
		)
		(pad "22" smd rect
			(at 2.925064 -2.275078 270)
			(size 0.4064 1.3716)
			(layers "F.Cu" "F.Mask" "F.Paste")
			(net "SMB_PEHPCPU1_LVC3_R3_SCL")
		)
		(pad "23" smd rect
			(at 2.925064 -2.925064 270)
			(size 0.4064 1.3716)
			(layers "F.Cu" "F.Mask" "F.Paste")
			(net "SMB_PEHPCPU1_LVC3_R3_SDA")
		)
		(pad "24" smd rect
			(at 2.925064 -3.674872 270)
			(size 0.6096 1.3716)
			(layers "F.Cu" "F.Mask" "F.Paste")
			(net "P3V3_AUX")
		)
	)
	(footprint ""
		(layer "F.Cu")
		(at 29.948124 -393.198858)
		(property "Reference" "R4656"
			(at 0 0 0)
			(layer "F.SilkS")
			(hide yes)
			(effects
				(font
					(size 1.27 1.27)
				)
			)
		)
		(property "Value" ""
			(at 0 0 0)
			(layer "F.Fab")
			(effects
				(font
					(size 1.27 1.27)
				)
			)
		)
		(duplicate_pad_numbers_are_jumpers no)
		(fp_line
			(start -0.7874 -0.4064)
			(end 0.7874 -0.4064)
			(stroke
				(width 0.1524)
				(type default)
			)
			(layer "F.SilkS")
		)
		(fp_line
			(start -0.7874 0.4064)
			(end -0.7874 -0.4064)
			(stroke
				(width 0.1524)
				(type default)
			)
			(layer "F.SilkS")
		)
		(fp_line
			(start 0.7874 -0.4064)
			(end 0.7874 0.4064)
			(stroke
				(width 0.1524)
				(type default)
			)
			(layer "F.SilkS")
		)
		(fp_line
			(start 0.7874 0.4064)
			(end -0.7874 0.4064)
			(stroke
				(width 0.1524)
				(type default)
			)
			(layer "F.SilkS")
		)
		(fp_line
			(start -0.67945 -0.305054)
			(end -0.12065 -0.305054)
			(stroke
				(width 0.1)
				(type default)
			)
			(layer "F.Fab")
		)
		(fp_line
			(start -0.67945 0.3048)
			(end -0.67945 -0.305054)
			(stroke
				(width 0.1)
				(type default)
			)
			(layer "F.Fab")
		)
		(fp_line
			(start -0.12065 -0.305054)
			(end -0.12065 -0.2794)
			(stroke
				(width 0.1)
				(type default)
			)
			(layer "F.Fab")
		)
		(fp_line
			(start -0.12065 -0.2794)
			(end 0.12065 -0.2794)
			(stroke
				(width 0.1)
				(type default)
			)
			(layer "F.Fab")
		)
		(fp_line
			(start -0.12065 0.2794)
			(end -0.12065 0.3048)
			(stroke
				(width 0.1)
				(type default)
			)
			(layer "F.Fab")
		)
		(fp_line
			(start -0.12065 0.3048)
			(end -0.67945 0.3048)
			(stroke
				(width 0.1)
				(type default)
			)
			(layer "F.Fab")
		)
		(fp_line
			(start 0.120396 0.2794)
			(end -0.12065 0.2794)
			(stroke
				(width 0.1)
				(type default)
			)
			(layer "F.Fab")
		)
		(fp_line
			(start 0.120396 0.3048)
			(end 0.120396 0.2794)
			(stroke
				(width 0.1)
				(type default)
			)
			(layer "F.Fab")
		)
		(fp_line
			(start 0.12065 -0.3048)
			(end 0.67945 -0.3048)
			(stroke
				(width 0.1)
				(type default)
			)
			(layer "F.Fab")
		)
		(fp_line
			(start 0.12065 -0.2794)
			(end 0.12065 -0.3048)
			(stroke
				(width 0.1)
				(type default)
			)
			(layer "F.Fab")
		)
		(fp_line
			(start 0.67945 -0.3048)
			(end 0.67945 0.3048)
			(stroke
				(width 0.1)
				(type default)
			)
			(layer "F.Fab")
		)
		(fp_line
			(start 0.67945 0.3048)
			(end 0.120396 0.3048)
			(stroke
				(width 0.1)
				(type default)
			)
			(layer "F.Fab")
		)
		(pad "1" smd circle
			(at -0.40005 0)
			(size 0 0)
			(layers "F.Cu" "F.Mask" "F.Paste")
			(net "P3V3_AUX")
		)
		(pad "2" smd circle
			(at 0.40005 0)
			(size 0 0)
			(layers "F.Cu" "F.Mask" "F.Paste")
			(net "FM_P2E_BUF2_SD_TH")
		)
	)
	(footprint ""
		(layer "F.Cu")
		(at 131.364736 -118.226078 -90)
		(property "Reference" "U50"
			(at 1.24968 -2.246884 0)
			(unlocked yes)
			(layer "F.SilkS")
			(effects
				(font
					(size 0.7874 0.5842)
					(thickness 0.1524)
				)
				(justify left)
			)
		)
		(property "Value" ""
			(at 0 0 270)
			(layer "F.Fab")
			(effects
				(font
					(size 1.27 1.27)
				)
			)
		)
		(duplicate_pad_numbers_are_jumpers no)
		(fp_line
			(start -1.733296 1.549908)
			(end 1.733296 1.549908)
			(stroke
				(width 0.1524)
				(type default)
			)
			(layer "F.SilkS")
		)
		(fp_line
			(start 1.733296 1.549908)
			(end 1.733296 -1.549908)
			(stroke
				(width 0.1524)
				(type default)
			)
			(layer "F.SilkS")
		)
		(fp_line
			(start 0 -0.889)
			(end -0.660908 -1.549908)
			(stroke
				(width 0.1524)
				(type default)
			)
			(layer "F.SilkS")
		)
		(fp_line
			(start -1.733296 -1.549908)
			(end -1.733296 1.549908)
			(stroke
				(width 0.1524)
				(type default)
			)
			(layer "F.SilkS")
		)
		(fp_line
			(start -0.660908 -1.549908)
			(end -1.733296 -1.549908)
			(stroke
				(width 0.1524)
				(type default)
			)
			(layer "F.SilkS")
		)
		(fp_line
			(start 0.660908 -1.549908)
			(end 0 -0.889)
			(stroke
				(width 0.1524)
				(type default)
			)
			(layer "F.SilkS")
		)
		(fp_line
			(start 1.733296 -1.549908)
			(end 0.660908 -1.549908)
			(stroke
				(width 0.1524)
				(type default)
			)
			(layer "F.SilkS")
		)
		(fp_poly
			(pts
				(xy -2.41046 -1.18618) (xy -1.90246 -0.93218) (xy -2.41046 -0.67818)
			)
			(stroke
				(width 0)
				(type default)
			)
			(fill yes)
			(layer "F.SilkS")
		)
		(fp_line
			(start -0.849884 1.549908)
			(end 0.849884 1.549908)
			(stroke
				(width 0.1)
				(type default)
			)
			(layer "F.Fab")
		)
		(fp_line
			(start 0.849884 1.549908)
			(end 0.849884 -1.549908)
			(stroke
				(width 0.1)
				(type default)
			)
			(layer "F.Fab")
		)
		(fp_line
			(start -0.849884 -1.549908)
			(end -0.849884 1.549908)
			(stroke
				(width 0.1)
				(type default)
			)
			(layer "F.Fab")
		)
		(fp_line
			(start 0.849884 -1.549908)
			(end -0.849884 -1.549908)
			(stroke
				(width 0.1)
				(type default)
			)
			(layer "F.Fab")
		)
		(fp_poly
			(pts
				(xy -2.4384 -1.20396) (xy -2.4384 -0.69596) (xy -1.9304 -0.94996)
			)
			(stroke
				(width 0)
				(type default)
			)
			(fill yes)
			(layer "F.Fab")
		)
		(pad "1" smd rect
			(at -1.199896 -0.94996 180)
			(size 0.5588 0.8128)
			(layers "F.Cu" "F.Mask" "F.Paste")
			(net "HP_OCP_V3_2_EN")
		)
		(pad "2" smd rect
			(at -1.199896 0 180)
			(size 0.5588 0.8128)
			(layers "F.Cu" "F.Mask" "F.Paste")
			(net "HP_LVC3_OCP_V3_2_PRSNT2")
		)
		(pad "3" smd rect
			(at -1.199896 0.94996 180)
			(size 0.5588 0.8128)
			(layers "F.Cu" "F.Mask" "F.Paste")
			(net "GND")
		)
		(pad "4" smd rect
			(at 1.199896 0.94996 180)
			(size 0.5588 0.8128)
			(layers "F.Cu" "F.Mask" "F.Paste")
			(net "HP_LVC3_OCP_V3_2_EN")
		)
		(pad "5" smd rect
			(at 1.199896 -0.94996 180)
			(size 0.5588 0.8128)
			(layers "F.Cu" "F.Mask" "F.Paste")
			(net "P3V3_AUX")
		)
	)
)
